# T6G (Grand Teton) — schematic netlist excerpt (pin names and nets, part order shuffled) for the footprints in the layout excerpt that follows; sources: Cadence DE-HDL packaged netlist, KiCad conversion of 04192023_DAF0TMB3IC0_F0TG_MB_C_brd_V02_OCP.brd

R6736  Q_RES  0 5% CHIP  pkg 0201LF  page 184 : A = SMB_RT_CPU1_P1_R_SDA ; B = SMB_RT_CPU1_P1_SDA
C2104  Q_CAP  22UF 4V 20% X6S  pkg C0402  page 74 : A = PVDDIO_P1 ; B = GND
R1156  Q_RES  33 5% EMPTY  pkg 0402LF  page 161 : A = SMB_APML_CPU0_R_SCL ; B = SMB_APML_CPU0_SCL

(kicad_pcb
	(version 20260206)
	(generator "pcbnew")
	(generator_version "10.0")
	(general
		(thickness 1.6)
		(legacy_teardrops no)
	)
	(paper "A4")
	(title_block
		(title "04192023_DAF0TMB3IC0_F0TG_MB_C_brd_V02_OCP.brd")
		(comment 1 "Grand Teton / footprints 6533-6535 of 8354")
	)
	(layers
		(0 "F.Cu" signal "TOP")
		(4 "In1.Cu" signal "GND")
		(6 "In2.Cu" signal "IN1")
		(8 "In3.Cu" signal "GND1")
		(10 "In4.Cu" signal "IN2")
		(12 "In5.Cu" signal "GND2")
		(14 "In6.Cu" signal "IN3")
		(16 "In7.Cu" signal "GND3")
		(18 "In8.Cu" signal "VCC")
		(20 "In9.Cu" signal "VCC1")
		(22 "In10.Cu" signal "GND4")
		(24 "In11.Cu" signal "IN4")
		(26 "In12.Cu" signal "GND5")
		(28 "In13.Cu" signal "IN5")
		(30 "In14.Cu" signal "GND6")
		(32 "In15.Cu" signal "IN6")
		(34 "In16.Cu" signal "GND7")
		(2 "B.Cu" signal "BOTTOM")
		(9 "F.Adhes" user "F.Adhesive")
		(11 "B.Adhes" user "B.Adhesive")
		(13 "F.Paste" user "Package Geometry/Pastemask Top")
		(15 "B.Paste" user "Package Geometry/Pastemask Bottom")
		(5 "F.SilkS" user "Ref Des/Silkscreen Top")
		(7 "B.SilkS" user "Ref Des/Silkscreen Bottom")
		(1 "F.Mask" user "Board Geometry/Soldermask Top")
		(3 "B.Mask" user "Board Geometry/Soldermask Bottom")
		(17 "Dwgs.User" user "User.Drawings")
		(19 "Cmts.User" user "User.Comments")
		(21 "Eco1.User" user "User.Eco1")
		(23 "Eco2.User" user "User.Eco2")
		(25 "Edge.Cuts" user "Board Geometry/Outline")
		(27 "Margin" user)
		(31 "F.CrtYd" user "Package Geometry/Place Bound Top")
		(29 "B.CrtYd" user "Package Geometry/Place Bound Bottom")
		(35 "F.Fab" user "Ref Des/Assembly Top")
		(33 "B.Fab" user "Ref Des/Assembly Bottom")
	)
	(footprint ""
		(layer "B.Cu")
		(at 237.617 -249.555)
		(property "Reference" "R1156"
			(at 0 0 0)
			(layer "B.SilkS")
			(hide yes)
			(effects
				(font
					(size 1.27 1.27)
				)
				(justify mirror)
			)
		)
		(property "Value" ""
			(at 0 0 0)
			(layer "B.Fab")
			(effects
				(font
					(size 1.27 1.27)
				)
				(justify mirror)
			)
		)
		(duplicate_pad_numbers_are_jumpers no)
		(fp_line
			(start -0.7874 -0.4064)
			(end -0.7874 0.4064)
			(stroke
				(width 0.1524)
				(type default)
			)
			(layer "B.SilkS")
		)
		(fp_line
			(start -0.7874 0.4064)
			(end 0.7874 0.4064)
			(stroke
				(width 0.1524)
				(type default)
			)
			(layer "B.SilkS")
		)
		(fp_line
			(start 0.7874 -0.4064)
			(end -0.7874 -0.4064)
			(stroke
				(width 0.1524)
				(type default)
			)
			(layer "B.SilkS")
		)
		(fp_line
			(start 0.7874 0.4064)
			(end 0.7874 -0.4064)
			(stroke
				(width 0.1524)
				(type default)
			)
			(layer "B.SilkS")
		)
		(fp_line
			(start -0.67945 -0.3048)
			(end -0.67945 0.3048)
			(stroke
				(width 0.1)
				(type default)
			)
			(layer "B.Fab")
		)
		(fp_line
			(start -0.67945 0.3048)
			(end -0.120396 0.3048)
			(stroke
				(width 0.1)
				(type default)
			)
			(layer "B.Fab")
		)
		(fp_line
			(start -0.12065 -0.3048)
			(end -0.67945 -0.3048)
			(stroke
				(width 0.1)
				(type default)
			)
			(layer "B.Fab")
		)
		(fp_line
			(start -0.12065 -0.2794)
			(end -0.12065 -0.3048)
			(stroke
				(width 0.1)
				(type default)
			)
			(layer "B.Fab")
		)
		(fp_line
			(start -0.120396 0.2794)
			(end 0.12065 0.2794)
			(stroke
				(width 0.1)
				(type default)
			)
			(layer "B.Fab")
		)
		(fp_line
			(start -0.120396 0.3048)
			(end -0.120396 0.2794)
			(stroke
				(width 0.1)
				(type default)
			)
			(layer "B.Fab")
		)
		(fp_line
			(start 0.12065 -0.305054)
			(end 0.12065 -0.2794)
			(stroke
				(width 0.1)
				(type default)
			)
			(layer "B.Fab")
		)
		(fp_line
			(start 0.12065 -0.2794)
			(end -0.12065 -0.2794)
			(stroke
				(width 0.1)
				(type default)
			)
			(layer "B.Fab")
		)
		(fp_line
			(start 0.12065 0.2794)
			(end 0.12065 0.3048)
			(stroke
				(width 0.1)
				(type default)
			)
			(layer "B.Fab")
		)
		(fp_line
			(start 0.12065 0.3048)
			(end 0.67945 0.3048)
			(stroke
				(width 0.1)
				(type default)
			)
			(layer "B.Fab")
		)
		(fp_line
			(start 0.67945 -0.305054)
			(end 0.12065 -0.305054)
			(stroke
				(width 0.1)
				(type default)
			)
			(layer "B.Fab")
		)
		(fp_line
			(start 0.67945 0.3048)
			(end 0.67945 -0.305054)
			(stroke
				(width 0.1)
				(type default)
			)
			(layer "B.Fab")
		)
		(pad "1" smd rect
			(at 0.40005 0)
			(size 0.4572 0.508)
			(layers "B.Cu" "B.Mask" "B.Paste")
			(net "SMB_APML_CPU0_R_SCL")
		)
		(pad "2" smd rect
			(at -0.40005 0)
			(size 0.4572 0.508)
			(layers "B.Cu" "B.Mask" "B.Paste")
			(net "SMB_APML_CPU0_SCL")
		)
	)
	(footprint ""
		(layer "B.Cu")
		(at 98.592386 -256.734564 180)
		(property "Reference" "C2104"
			(at 0 0 0)
			(layer "B.SilkS")
			(hide yes)
			(effects
				(font
					(size 1.27 1.27)
				)
				(justify mirror)
			)
		)
		(property "Value" ""
			(at 0 0 0)
			(layer "B.Fab")
			(effects
				(font
					(size 1.27 1.27)
				)
				(justify mirror)
			)
		)
		(duplicate_pad_numbers_are_jumpers no)
		(fp_line
			(start 0.7874 0.4064)
			(end 0.7874 -0.4064)
			(stroke
				(width 0.1524)
				(type default)
			)
			(layer "B.SilkS")
		)
		(fp_line
			(start 0.7874 -0.4064)
			(end -0.7874 -0.4064)
			(stroke
				(width 0.1524)
				(type default)
			)
			(layer "B.SilkS")
		)
		(fp_line
			(start -0.7874 0.4064)
			(end 0.7874 0.4064)
			(stroke
				(width 0.1524)
				(type default)
			)
			(layer "B.SilkS")
		)
		(fp_line
			(start -0.7874 -0.4064)
			(end -0.7874 0.4064)
			(stroke
				(width 0.1524)
				(type default)
			)
			(layer "B.SilkS")
		)
		(fp_line
			(start 0.67945 0.3048)
			(end 0.67945 -0.305054)
			(stroke
				(width 0.1)
				(type default)
			)
			(layer "B.Fab")
		)
		(fp_line
			(start 0.67945 -0.305054)
			(end 0.12065 -0.305054)
			(stroke
				(width 0.1)
				(type default)
			)
			(layer "B.Fab")
		)
		(fp_line
			(start 0.12065 0.3048)
			(end 0.67945 0.3048)
			(stroke
				(width 0.1)
				(type default)
			)
			(layer "B.Fab")
		)
		(fp_line
			(start 0.12065 0.2794)
			(end 0.12065 0.3048)
			(stroke
				(width 0.1)
				(type default)
			)
			(layer "B.Fab")
		)
		(fp_line
			(start 0.12065 -0.2794)
			(end -0.12065 -0.2794)
			(stroke
				(width 0.1)
				(type default)
			)
			(layer "B.Fab")
		)
		(fp_line
			(start 0.12065 -0.305054)
			(end 0.12065 -0.2794)
			(stroke
				(width 0.1)
				(type default)
			)
			(layer "B.Fab")
		)
		(fp_line
			(start -0.120396 0.3048)
			(end -0.120396 0.2794)
			(stroke
				(width 0.1)
				(type default)
			)
			(layer "B.Fab")
		)
		(fp_line
			(start -0.120396 0.2794)
			(end 0.12065 0.2794)
			(stroke
				(width 0.1)
				(type default)
			)
			(layer "B.Fab")
		)
		(fp_line
			(start -0.12065 -0.2794)
			(end -0.12065 -0.3048)
			(stroke
				(width 0.1)
				(type default)
			)
			(layer "B.Fab")
		)
		(fp_line
			(start -0.12065 -0.3048)
			(end -0.67945 -0.3048)
			(stroke
				(width 0.1)
				(type default)
			)
			(layer "B.Fab")
		)
		(fp_line
			(start -0.67945 0.3048)
			(end -0.120396 0.3048)
			(stroke
				(width 0.1)
				(type default)
			)
			(layer "B.Fab")
		)
		(fp_line
			(start -0.67945 -0.3048)
			(end -0.67945 0.3048)
			(stroke
				(width 0.1)
				(type default)
			)
			(layer "B.Fab")
		)
		(pad "1" smd circle
			(at 0.40005 0)
			(size 0 0)
			(layers "B.Cu" "B.Mask" "B.Paste")
			(net "PVDDIO_P1")
		)
		(pad "2" smd circle
			(at -0.40005 0)
			(size 0 0)
			(layers "B.Cu" "B.Mask" "B.Paste")
			(net "GND")
		)
	)
	(footprint ""
		(layer "B.Cu")
		(at 218.059 -336.296 180)
		(property "Reference" "R6736"
			(at 0 0 0)
			(layer "B.SilkS")
			(hide yes)
			(effects
				(font
					(size 1.27 1.27)
				)
				(justify mirror)
			)
		)
		(property "Value" ""
			(at 0 0 0)
			(layer "B.Fab")
			(effects
				(font
					(size 1.27 1.27)
				)
				(justify mirror)
			)
		)
		(duplicate_pad_numbers_are_jumpers no)
		(fp_line
			(start 0.32512 0.175006)
			(end 0.32512 -0.175006)
			(stroke
				(width 0.1)
				(type default)
			)
			(layer "B.Fab")
		)
		(fp_line
			(start 0.32512 -0.175006)
			(end -0.32512 -0.175006)
			(stroke
				(width 0.1)
				(type default)
			)
			(layer "B.Fab")
		)
		(fp_line
			(start -0.32512 0.175006)
			(end 0.32512 0.175006)
			(stroke
				(width 0.1)
				(type default)
			)
			(layer "B.Fab")
		)
		(fp_line
			(start -0.32512 -0.175006)
			(end -0.32512 0.175006)
			(stroke
				(width 0.1)
				(type default)
			)
			(layer "B.Fab")
		)
		(pad "1" smd rect
			(at 0.2667 0)
			(size 0.3048 0.381)
			(layers "B.Cu" "B.Mask" "B.Paste")
			(net "SMB_RT_CPU1_P1_R_SDA")
		)
		(pad "2" smd rect
			(at -0.2667 0 180)
			(size 0.3048 0.381)
			(layers "B.Cu" "B.Mask" "B.Paste")
			(net "SMB_RT_CPU1_P1_SDA")
		)
	)
)
